FILE_TYPE = CONNECTIVITY;
{Allegro Design Entry HDL 16.6-p007 (v16-6-112F) 10/10/2012}
"PAGE_NUMBER" = 34;
0"NC";
1"UPI_CPU0_CPU1_P1P1_DN<19..0>";
2"UPI_CPU0_CPU1_P1P1_DP<19..0>";
3"UPI_CPU1_CPU0_P1P1_DN<19..0>";
4"UPI_CPU1_CPU0_P1P1_DP<19..0>";
5"UPI_CPU1_CPU0_P1P1_DN<19>";
6"UPI_CPU1_CPU0_P1P1_DN<18>";
7"UPI_CPU1_CPU0_P1P1_DN<17>";
8"UPI_CPU1_CPU0_P1P1_DN<16>";
9"UPI_CPU1_CPU0_P1P1_DN<15>";
10"UPI_CPU1_CPU0_P1P1_DN<14>";
11"UPI_CPU1_CPU0_P1P1_DN<13>";
12"UPI_CPU1_CPU0_P1P1_DN<12>";
13"UPI_CPU1_CPU0_P1P1_DN<11>";
14"UPI_CPU1_CPU0_P1P1_DN<10>";
15"UPI_CPU1_CPU0_P1P1_DP<19>";
16"UPI_CPU1_CPU0_P1P1_DP<18>";
17"UPI_CPU1_CPU0_P1P1_DP<17>";
18"UPI_CPU1_CPU0_P1P1_DP<16>";
19"UPI_CPU1_CPU0_P1P1_DP<15>";
20"UPI_CPU1_CPU0_P1P1_DP<14>";
21"UPI_CPU1_CPU0_P1P1_DP<13>";
22"UPI_CPU1_CPU0_P1P1_DP<12>";
23"UPI_CPU1_CPU0_P1P1_DP<11>";
24"UPI_CPU1_CPU0_P1P1_DP<10>";
25"UPI_CPU1_CPU0_P1P1_DP<9>";
26"UPI_CPU1_CPU0_P1P1_DP<8>";
27"UPI_CPU1_CPU0_P1P1_DP<7>";
28"UPI_CPU1_CPU0_P1P1_DP<6>";
29"UPI_CPU1_CPU0_P1P1_DP<5>";
30"UPI_CPU1_CPU0_P1P1_DP<4>";
31"UPI_CPU1_CPU0_P1P1_DP<3>";
32"UPI_CPU1_CPU0_P1P1_DP<2>";
33"UPI_CPU1_CPU0_P1P1_DP<1>";
34"UPI_CPU1_CPU0_P1P1_DP<0>";
35"UPI_CPU1_CPU0_P1P1_DN<9>";
36"UPI_CPU1_CPU0_P1P1_DN<8>";
37"UPI_CPU1_CPU0_P1P1_DN<7>";
38"UPI_CPU1_CPU0_P1P1_DN<6>";
39"UPI_CPU1_CPU0_P1P1_DN<5>";
40"UPI_CPU1_CPU0_P1P1_DN<4>";
41"UPI_CPU1_CPU0_P1P1_DN<3>";
42"UPI_CPU1_CPU0_P1P1_DN<2>";
43"UPI_CPU1_CPU0_P1P1_DN<1>";
44"UPI_CPU1_CPU0_P1P1_DN<0>";
45"UPI_CPU0_CPU1_P1P1_DN<19>";
46"UPI_CPU0_CPU1_P1P1_DN<18>";
47"UPI_CPU0_CPU1_P1P1_DN<17>";
48"UPI_CPU0_CPU1_P1P1_DN<16>";
49"UPI_CPU0_CPU1_P1P1_DN<15>";
50"UPI_CPU0_CPU1_P1P1_DN<14>";
51"UPI_CPU0_CPU1_P1P1_DN<13>";
52"UPI_CPU0_CPU1_P1P1_DN<12>";
53"UPI_CPU0_CPU1_P1P1_DN<11>";
54"UPI_CPU0_CPU1_P1P1_DN<10>";
55"UPI_CPU0_CPU1_P1P1_DP<19>";
56"UPI_CPU0_CPU1_P1P1_DP<18>";
57"UPI_CPU0_CPU1_P1P1_DP<17>";
58"UPI_CPU0_CPU1_P1P1_DP<16>";
59"UPI_CPU0_CPU1_P1P1_DP<15>";
60"UPI_CPU0_CPU1_P1P1_DP<14>";
61"UPI_CPU0_CPU1_P1P1_DP<13>";
62"UPI_CPU0_CPU1_P1P1_DP<12>";
63"UPI_CPU0_CPU1_P1P1_DP<11>";
64"UPI_CPU0_CPU1_P1P1_DP<10>";
65"UPI_CPU0_CPU1_P1P1_DP<9>";
66"UPI_CPU0_CPU1_P1P1_DP<8>";
67"UPI_CPU0_CPU1_P1P1_DP<7>";
68"UPI_CPU0_CPU1_P1P1_DP<6>";
69"UPI_CPU0_CPU1_P1P1_DP<5>";
70"UPI_CPU0_CPU1_P1P1_DP<4>";
71"UPI_CPU0_CPU1_P1P1_DP<3>";
72"UPI_CPU0_CPU1_P1P1_DP<2>";
73"UPI_CPU0_CPU1_P1P1_DP<1>";
74"UPI_CPU0_CPU1_P1P1_DP<0>";
75"UPI_CPU0_CPU1_P1P1_DN<9>";
76"UPI_CPU0_CPU1_P1P1_DN<8>";
77"UPI_CPU0_CPU1_P1P1_DN<7>";
78"UPI_CPU0_CPU1_P1P1_DN<6>";
79"UPI_CPU0_CPU1_P1P1_DN<5>";
80"UPI_CPU0_CPU1_P1P1_DN<4>";
81"UPI_CPU0_CPU1_P1P1_DN<3>";
82"UPI_CPU0_CPU1_P1P1_DN<2>";
83"UPI_CPU0_CPU1_P1P1_DN<1>";
84"UPI_CPU0_CPU1_P1P1_DN<0>";
%"TAP"
"1","(-5300,1925)","2","mstr_standard","I10";
;
HDL_TAP"TRUE"
BODY_TYPE"PLUMBING"
CDS_LIB"mstr_standard";
"B \NAC \NWC"3;
"S \NAC"
BN"12"12;
%"TAP"
"1","(-5300,1825)","2","mstr_standard","I11";
;
HDL_TAP"TRUE"
BODY_TYPE"PLUMBING"
CDS_LIB"mstr_standard";
"B \NAC \NWC"3;
"S \NAC"
BN"14"10;
%"TAP"
"1","(-5300,1975)","2","mstr_standard","I12";
;
HDL_TAP"TRUE"
BODY_TYPE"PLUMBING"
CDS_LIB"mstr_standard";
"B \NAC \NWC"3;
"S \NAC"
BN"11"13;
%"TAP"
"1","(-5300,2025)","2","mstr_standard","I13";
;
HDL_TAP"TRUE"
BODY_TYPE"PLUMBING"
CDS_LIB"mstr_standard";
"B \NAC \NWC"3;
"S \NAC"
BN"10"14;
%"TAP"
"1","(-5300,2075)","2","mstr_standard","I14";
;
HDL_TAP"TRUE"
BODY_TYPE"PLUMBING"
CDS_LIB"mstr_standard";
"B \NAC \NWC"3;
"S \NAC"
BN"9"35;
%"TAP"
"1","(-5300,2125)","2","mstr_standard","I15";
;
HDL_TAP"TRUE"
BODY_TYPE"PLUMBING"
CDS_LIB"mstr_standard";
"B \NAC \NWC"3;
"S \NAC"
BN"8"36;
%"TAP"
"1","(-5300,2175)","2","mstr_standard","I16";
;
HDL_TAP"TRUE"
BODY_TYPE"PLUMBING"
CDS_LIB"mstr_standard";
"B \NAC \NWC"3;
"S \NAC"
BN"7"37;
%"TAP"
"1","(-5300,2225)","2","mstr_standard","I17";
;
HDL_TAP"TRUE"
BODY_TYPE"PLUMBING"
CDS_LIB"mstr_standard";
"B \NAC \NWC"3;
"S \NAC"
BN"6"38;
%"TAP"
"1","(-5300,2275)","2","mstr_standard","I18";
;
HDL_TAP"TRUE"
BODY_TYPE"PLUMBING"
CDS_LIB"mstr_standard";
"B \NAC \NWC"3;
"S \NAC"
BN"5"39;
%"TAP"
"1","(-5300,2325)","2","mstr_standard","I19";
;
HDL_TAP"TRUE"
BODY_TYPE"PLUMBING"
CDS_LIB"mstr_standard";
"B \NAC \NWC"3;
"S \NAC"
BN"4"40;
%"TAP"
"1","(-5300,2375)","2","mstr_standard","I20";
;
HDL_TAP"TRUE"
BODY_TYPE"PLUMBING"
CDS_LIB"mstr_standard";
"B \NAC \NWC"3;
"S \NAC"
BN"3"41;
%"TAP"
"1","(-5300,2425)","2","mstr_standard","I21";
;
HDL_TAP"TRUE"
BODY_TYPE"PLUMBING"
CDS_LIB"mstr_standard";
"B \NAC \NWC"3;
"S \NAC"
BN"2"42;
%"TAP"
"1","(-5300,2475)","2","mstr_standard","I22";
;
HDL_TAP"TRUE"
BODY_TYPE"PLUMBING"
CDS_LIB"mstr_standard";
"B \NAC \NWC"3;
"S \NAC"
BN"1"43;
%"TAP"
"1","(-5300,2525)","2","mstr_standard","I23";
;
HDL_TAP"TRUE"
BODY_TYPE"PLUMBING"
CDS_LIB"mstr_standard";
"B \NAC \NWC"3;
"S \NAC"
BN"0"44;
%"TAP"
"1","(-5300,2625)","2","mstr_standard","I24";
;
HDL_TAP"TRUE"
BODY_TYPE"PLUMBING"
CDS_LIB"mstr_standard";
"B \NAC \NWC"4;
"S \NAC"
BN"19"15;
%"TAP"
"1","(-5300,2775)","2","mstr_standard","I25";
;
HDL_TAP"TRUE"
BODY_TYPE"PLUMBING"
CDS_LIB"mstr_standard";
"B \NAC \NWC"4;
"S \NAC"
BN"16"18;
%"TAP"
"1","(-5300,2725)","2","mstr_standard","I26";
;
HDL_TAP"TRUE"
BODY_TYPE"PLUMBING"
CDS_LIB"mstr_standard";
"B \NAC \NWC"4;
"S \NAC"
BN"17"17;
%"TAP"
"1","(-5300,2675)","2","mstr_standard","I27";
;
HDL_TAP"TRUE"
BODY_TYPE"PLUMBING"
CDS_LIB"mstr_standard";
"B \NAC \NWC"4;
"S \NAC"
BN"18"16;
%"TAP"
"1","(-5300,2825)","2","mstr_standard","I28";
;
HDL_TAP"TRUE"
BODY_TYPE"PLUMBING"
CDS_LIB"mstr_standard";
"B \NAC \NWC"4;
"S \NAC"
BN"15"19;
%"TAP"
"1","(-5300,2875)","2","mstr_standard","I29";
;
HDL_TAP"TRUE"
BODY_TYPE"PLUMBING"
CDS_LIB"mstr_standard";
"B \NAC \NWC"4;
"S \NAC"
BN"14"20;
%"TAP"
"1","(-5300,1625)","2","mstr_standard","I3";
;
HDL_TAP"TRUE"
BODY_TYPE"PLUMBING"
CDS_LIB"mstr_standard";
"B \NAC \NWC"3;
"S \NAC"
BN"18"6;
%"TAP"
"1","(-5300,2925)","2","mstr_standard","I30";
;
HDL_TAP"TRUE"
BODY_TYPE"PLUMBING"
CDS_LIB"mstr_standard";
"B \NAC \NWC"4;
"S \NAC"
BN"13"21;
%"TAP"
"1","(-5300,2975)","2","mstr_standard","I31";
;
HDL_TAP"TRUE"
BODY_TYPE"PLUMBING"
CDS_LIB"mstr_standard";
"B \NAC \NWC"4;
"S \NAC"
BN"12"22;
%"TAP"
"1","(-5300,3075)","2","mstr_standard","I32";
;
HDL_TAP"TRUE"
BODY_TYPE"PLUMBING"
CDS_LIB"mstr_standard";
"B \NAC \NWC"4;
"S \NAC"
BN"10"24;
%"TAP"
"1","(-5300,3025)","2","mstr_standard","I33";
;
HDL_TAP"TRUE"
BODY_TYPE"PLUMBING"
CDS_LIB"mstr_standard";
"B \NAC \NWC"4;
"S \NAC"
BN"11"23;
%"TAP"
"1","(-5300,3125)","2","mstr_standard","I34";
;
HDL_TAP"TRUE"
BODY_TYPE"PLUMBING"
CDS_LIB"mstr_standard";
"B \NAC \NWC"4;
"S \NAC"
BN"9"25;
%"TAP"
"1","(-5300,3175)","2","mstr_standard","I35";
;
HDL_TAP"TRUE"
BODY_TYPE"PLUMBING"
CDS_LIB"mstr_standard";
"B \NAC \NWC"4;
"S \NAC"
BN"8"26;
%"TAP"
"1","(-5300,3225)","2","mstr_standard","I36";
;
HDL_TAP"TRUE"
BODY_TYPE"PLUMBING"
CDS_LIB"mstr_standard";
"B \NAC \NWC"4;
"S \NAC"
BN"7"27;
%"TAP"
"1","(-5300,3325)","2","mstr_standard","I37";
;
HDL_TAP"TRUE"
BODY_TYPE"PLUMBING"
CDS_LIB"mstr_standard";
"B \NAC \NWC"4;
"S \NAC"
BN"5"29;
%"TAP"
"1","(-5300,3275)","2","mstr_standard","I38";
;
HDL_TAP"TRUE"
BODY_TYPE"PLUMBING"
CDS_LIB"mstr_standard";
"B \NAC \NWC"4;
"S \NAC"
BN"6"28;
%"TAP"
"1","(-5300,3375)","2","mstr_standard","I39";
;
HDL_TAP"TRUE"
BODY_TYPE"PLUMBING"
CDS_LIB"mstr_standard";
"B \NAC \NWC"4;
"S \NAC"
BN"4"30;
%"TAP"
"1","(-5300,1575)","2","mstr_standard","I4";
;
HDL_TAP"TRUE"
BODY_TYPE"PLUMBING"
CDS_LIB"mstr_standard";
"B \NAC \NWC"3;
"S \NAC"
BN"19"5;
%"TAP"
"1","(-5300,3425)","2","mstr_standard","I40";
;
HDL_TAP"TRUE"
BODY_TYPE"PLUMBING"
CDS_LIB"mstr_standard";
"B \NAC \NWC"4;
"S \NAC"
BN"3"31;
%"TAP"
"1","(-5300,3475)","2","mstr_standard","I41";
;
HDL_TAP"TRUE"
BODY_TYPE"PLUMBING"
CDS_LIB"mstr_standard";
"B \NAC \NWC"4;
"S \NAC"
BN"2"32;
%"TAP"
"1","(-5300,3575)","2","mstr_standard","I42";
;
HDL_TAP"TRUE"
BODY_TYPE"PLUMBING"
CDS_LIB"mstr_standard";
"B \NAC \NWC"4;
"S \NAC"
BN"0"34;
%"TAP"
"1","(-5300,3525)","2","mstr_standard","I43";
;
HDL_TAP"TRUE"
BODY_TYPE"PLUMBING"
CDS_LIB"mstr_standard";
"B \NAC \NWC"4;
"S \NAC"
BN"1"33;
%"TAP"
"1","(-2975,1575)","0","mstr_standard","I44";
;
HDL_TAP"TRUE"
BODY_TYPE"PLUMBING"
CDS_LIB"mstr_standard";
"B \NAC \NWC"1;
"S \NAC"
BN"19"45;
%"TAP"
"1","(-2975,1625)","0","mstr_standard","I45";
;
HDL_TAP"TRUE"
BODY_TYPE"PLUMBING"
CDS_LIB"mstr_standard";
"B \NAC \NWC"1;
"S \NAC"
BN"18"46;
%"TAP"
"1","(-2975,1675)","0","mstr_standard","I46";
;
HDL_TAP"TRUE"
BODY_TYPE"PLUMBING"
CDS_LIB"mstr_standard";
"B \NAC \NWC"1;
"S \NAC"
BN"17"47;
%"TAP"
"1","(-2975,1725)","0","mstr_standard","I47";
;
HDL_TAP"TRUE"
BODY_TYPE"PLUMBING"
CDS_LIB"mstr_standard";
"B \NAC \NWC"1;
"S \NAC"
BN"16"48;
%"TAP"
"1","(-2975,1775)","0","mstr_standard","I48";
;
HDL_TAP"TRUE"
BODY_TYPE"PLUMBING"
CDS_LIB"mstr_standard";
"B \NAC \NWC"1;
"S \NAC"
BN"15"49;
%"TAP"
"1","(-2975,1825)","0","mstr_standard","I49";
;
HDL_TAP"TRUE"
BODY_TYPE"PLUMBING"
CDS_LIB"mstr_standard";
"B \NAC \NWC"1;
"S \NAC"
BN"14"50;
%"TAP"
"1","(-5300,1675)","2","mstr_standard","I5";
;
HDL_TAP"TRUE"
BODY_TYPE"PLUMBING"
CDS_LIB"mstr_standard";
"B \NAC \NWC"3;
"S \NAC"
BN"17"7;
%"TAP"
"1","(-2975,1875)","0","mstr_standard","I50";
;
HDL_TAP"TRUE"
BODY_TYPE"PLUMBING"
CDS_LIB"mstr_standard";
"B \NAC \NWC"1;
"S \NAC"
BN"13"51;
%"TAP"
"1","(-2975,1925)","0","mstr_standard","I51";
;
HDL_TAP"TRUE"
BODY_TYPE"PLUMBING"
CDS_LIB"mstr_standard";
"B \NAC \NWC"1;
"S \NAC"
BN"12"52;
%"TAP"
"1","(-2975,1975)","0","mstr_standard","I52";
;
HDL_TAP"TRUE"
BODY_TYPE"PLUMBING"
CDS_LIB"mstr_standard";
"B \NAC \NWC"1;
"S \NAC"
BN"11"53;
%"TAP"
"1","(-2975,2025)","0","mstr_standard","I53";
;
HDL_TAP"TRUE"
BODY_TYPE"PLUMBING"
CDS_LIB"mstr_standard";
"B \NAC \NWC"1;
"S \NAC"
BN"10"54;
%"TAP"
"1","(-2975,2075)","0","mstr_standard","I54";
;
HDL_TAP"TRUE"
BODY_TYPE"PLUMBING"
CDS_LIB"mstr_standard";
"B \NAC \NWC"1;
"S \NAC"
BN"9"75;
%"TAP"
"1","(-2975,2125)","0","mstr_standard","I55";
;
HDL_TAP"TRUE"
BODY_TYPE"PLUMBING"
CDS_LIB"mstr_standard";
"B \NAC \NWC"1;
"S \NAC"
BN"8"76;
%"TAP"
"1","(-2975,2175)","0","mstr_standard","I56";
;
HDL_TAP"TRUE"
BODY_TYPE"PLUMBING"
CDS_LIB"mstr_standard";
"B \NAC \NWC"1;
"S \NAC"
BN"7"77;
%"TAP"
"1","(-2975,2225)","0","mstr_standard","I57";
;
HDL_TAP"TRUE"
BODY_TYPE"PLUMBING"
CDS_LIB"mstr_standard";
"B \NAC \NWC"1;
"S \NAC"
BN"6"78;
%"TAP"
"1","(-2975,2275)","0","mstr_standard","I58";
;
HDL_TAP"TRUE"
BODY_TYPE"PLUMBING"
CDS_LIB"mstr_standard";
"B \NAC \NWC"1;
"S \NAC"
BN"5"79;
%"TAP"
"1","(-2975,2325)","0","mstr_standard","I59";
;
HDL_TAP"TRUE"
BODY_TYPE"PLUMBING"
CDS_LIB"mstr_standard";
"B \NAC \NWC"1;
"S \NAC"
BN"4"80;
%"TAP"
"1","(-5300,1725)","2","mstr_standard","I6";
;
HDL_TAP"TRUE"
BODY_TYPE"PLUMBING"
CDS_LIB"mstr_standard";
"B \NAC \NWC"3;
"S \NAC"
BN"16"8;
%"TAP"
"1","(-2975,2375)","0","mstr_standard","I60";
;
HDL_TAP"TRUE"
BODY_TYPE"PLUMBING"
CDS_LIB"mstr_standard";
"B \NAC \NWC"1;
"S \NAC"
BN"3"81;
%"TAP"
"1","(-2975,2425)","0","mstr_standard","I61";
;
HDL_TAP"TRUE"
BODY_TYPE"PLUMBING"
CDS_LIB"mstr_standard";
"B \NAC \NWC"1;
"S \NAC"
BN"2"82;
%"TAP"
"1","(-2975,2475)","0","mstr_standard","I62";
;
HDL_TAP"TRUE"
BODY_TYPE"PLUMBING"
CDS_LIB"mstr_standard";
"B \NAC \NWC"1;
"S \NAC"
BN"1"83;
%"TAP"
"1","(-2975,2525)","0","mstr_standard","I63";
;
HDL_TAP"TRUE"
BODY_TYPE"PLUMBING"
CDS_LIB"mstr_standard";
"B \NAC \NWC"1;
"S \NAC"
BN"0"84;
%"TAP"
"1","(-2975,2625)","0","mstr_standard","I64";
;
HDL_TAP"TRUE"
BODY_TYPE"PLUMBING"
CDS_LIB"mstr_standard";
"B \NAC \NWC"2;
"S \NAC"
BN"19"55;
%"TAP"
"1","(-2975,2675)","0","mstr_standard","I65";
;
HDL_TAP"TRUE"
BODY_TYPE"PLUMBING"
CDS_LIB"mstr_standard";
"B \NAC \NWC"2;
"S \NAC"
BN"18"56;
%"TAP"
"1","(-2975,2725)","0","mstr_standard","I66";
;
HDL_TAP"TRUE"
BODY_TYPE"PLUMBING"
CDS_LIB"mstr_standard";
"B \NAC \NWC"2;
"S \NAC"
BN"17"57;
%"TAP"
"1","(-2975,2775)","0","mstr_standard","I67";
;
HDL_TAP"TRUE"
BODY_TYPE"PLUMBING"
CDS_LIB"mstr_standard";
"B \NAC \NWC"2;
"S \NAC"
BN"16"58;
%"TAP"
"1","(-2975,2825)","0","mstr_standard","I68";
;
HDL_TAP"TRUE"
BODY_TYPE"PLUMBING"
CDS_LIB"mstr_standard";
"B \NAC \NWC"2;
"S \NAC"
BN"15"59;
%"TAP"
"1","(-2975,2875)","0","mstr_standard","I69";
;
HDL_TAP"TRUE"
BODY_TYPE"PLUMBING"
CDS_LIB"mstr_standard";
"B \NAC \NWC"2;
"S \NAC"
BN"14"60;
%"TAP"
"1","(-5300,1775)","2","mstr_standard","I7";
;
HDL_TAP"TRUE"
BODY_TYPE"PLUMBING"
CDS_LIB"mstr_standard";
"B \NAC \NWC"3;
"S \NAC"
BN"15"9;
%"TAP"
"1","(-2975,2925)","0","mstr_standard","I70";
;
HDL_TAP"TRUE"
BODY_TYPE"PLUMBING"
CDS_LIB"mstr_standard";
"B \NAC \NWC"2;
"S \NAC"
BN"13"61;
%"TAP"
"1","(-2975,2975)","0","mstr_standard","I71";
;
HDL_TAP"TRUE"
BODY_TYPE"PLUMBING"
CDS_LIB"mstr_standard";
"B \NAC \NWC"2;
"S \NAC"
BN"12"62;
%"TAP"
"1","(-2975,3025)","0","mstr_standard","I72";
;
HDL_TAP"TRUE"
BODY_TYPE"PLUMBING"
CDS_LIB"mstr_standard";
"B \NAC \NWC"2;
"S \NAC"
BN"11"63;
%"TAP"
"1","(-2975,3075)","0","mstr_standard","I73";
;
HDL_TAP"TRUE"
BODY_TYPE"PLUMBING"
CDS_LIB"mstr_standard";
"B \NAC \NWC"2;
"S \NAC"
BN"10"64;
%"TAP"
"1","(-2975,3125)","0","mstr_standard","I74";
;
HDL_TAP"TRUE"
BODY_TYPE"PLUMBING"
CDS_LIB"mstr_standard";
"B \NAC \NWC"2;
"S \NAC"
BN"9"65;
%"TAP"
"1","(-2975,3225)","0","mstr_standard","I75";
;
HDL_TAP"TRUE"
BODY_TYPE"PLUMBING"
CDS_LIB"mstr_standard";
"B \NAC \NWC"2;
"S \NAC"
BN"7"67;
%"TAP"
"1","(-2975,3175)","0","mstr_standard","I76";
;
HDL_TAP"TRUE"
BODY_TYPE"PLUMBING"
CDS_LIB"mstr_standard";
"B \NAC \NWC"2;
"S \NAC"
BN"8"66;
%"TAP"
"1","(-2975,3275)","0","mstr_standard","I77";
;
HDL_TAP"TRUE"
BODY_TYPE"PLUMBING"
CDS_LIB"mstr_standard";
"B \NAC \NWC"2;
"S \NAC"
BN"6"68;
%"TAP"
"1","(-2975,3325)","0","mstr_standard","I78";
;
HDL_TAP"TRUE"
BODY_TYPE"PLUMBING"
CDS_LIB"mstr_standard";
"B \NAC \NWC"2;
"S \NAC"
BN"5"69;
%"TAP"
"1","(-2975,3375)","0","mstr_standard","I79";
;
HDL_TAP"TRUE"
BODY_TYPE"PLUMBING"
CDS_LIB"mstr_standard";
"B \NAC \NWC"2;
"S \NAC"
BN"4"70;
%"TAP"
"1","(-2975,3475)","0","mstr_standard","I80";
;
HDL_TAP"TRUE"
BODY_TYPE"PLUMBING"
CDS_LIB"mstr_standard";
"B \NAC \NWC"2;
"S \NAC"
BN"2"72;
%"TAP"
"1","(-2975,3425)","0","mstr_standard","I81";
;
HDL_TAP"TRUE"
BODY_TYPE"PLUMBING"
CDS_LIB"mstr_standard";
"B \NAC \NWC"2;
"S \NAC"
BN"3"71;
%"TAP"
"1","(-2975,3525)","0","mstr_standard","I82";
;
HDL_TAP"TRUE"
BODY_TYPE"PLUMBING"
CDS_LIB"mstr_standard";
"B \NAC \NWC"2;
"S \NAC"
BN"1"73;
%"TAP"
"1","(-2975,3575)","0","mstr_standard","I83";
;
HDL_TAP"TRUE"
BODY_TYPE"PLUMBING"
CDS_LIB"mstr_standard";
"B \NAC \NWC"2;
"S \NAC"
BN"0"74;
%"SKX_EXT_B"
"14","(-4100,2575)","0","chpset_lib","I86";
;
CDS_SEC"14"
ROOM"CPU0"
CDS_LOCATION"U5D1"
SEC"14"
SEC_TYPE"BGA1"
CDS_LIB"chpset_lib"
PACK_TYPE"BGA1"
MATERIAL"IC"
PART_NUMBER"TBD"
LOCATION"U5D1";
"UPI1_TX_DP<0>"
$PN"P3"55;
"UPI1_TX_DP<1>"
$PN"K3"56;
"UPI1_TX_DP<2>"
$PN"M5"57;
"UPI1_TX_DP<3>"
$PN"H5"58;
"UPI1_TX_DP<4>"
$PN"F7"59;
"UPI1_TX_DP<5>"
$PN"K7"60;
"UPI1_TX_DP<6>"
$PN"J8"61;
"UPI1_TX_DP<7>"
$PN"F9"62;
"UPI1_TX_DP<8>"
$PN"E10"63;
"UPI1_TX_DP<9>"
$PN"H9"64;
"UPI1_TX_DP<10>"
$PN"G12"65;
"UPI1_TX_DP<11>"
$PN"F13"66;
"UPI1_TX_DP<12>"
$PN"E14"67;
"UPI1_TX_DP<13>"
$PN"H15"68;
"UPI1_TX_DP<14>"
$PN"G16"69;
"UPI1_TX_DP<15>"
$PN"L18"70;
"UPI1_TX_DP<16>"
$PN"J18"71;
"UPI1_TX_DP<17>"
$PN"H19"72;
"UPI1_TX_DP<18>"
$PN"G20"73;
"UPI1_TX_DP<19>"
$PN"K21"74;
"UPI1_TX_DN<0>"
$PN"M3"45;
"UPI1_TX_DN<1>"
$PN"L4"46;
"UPI1_TX_DN<2>"
$PN"K5"47;
"UPI1_TX_DN<3>"
$PN"J6"48;
"UPI1_TX_DN<4>"
$PN"G6"49;
"UPI1_TX_DN<5>"
$PN"H7"50;
"UPI1_TX_DN<6>"
$PN"K9"51;
"UPI1_TX_DN<7>"
$PN"D9"52;
"UPI1_TX_DN<8>"
$PN"F11"53;
"UPI1_TX_DN<9>"
$PN"G10"54;
"UPI1_TX_DN<10>"
$PN"E12"75;
"UPI1_TX_DN<11>"
$PN"G14"76;
"UPI1_TX_DN<12>"
$PN"D15"77;
"UPI1_TX_DN<13>"
$PN"F15"78;
"UPI1_TX_DN<14>"
$PN"H17"79;
"UPI1_TX_DN<15>"
$PN"K19"80;
"UPI1_TX_DN<16>"
$PN"G18"81;
"UPI1_TX_DN<17>"
$PN"J20"82;
"UPI1_TX_DN<18>"
$PN"F21"83;
"UPI1_TX_DN<19>"
$PN"H21"84;
"UPI1_RX_DP<0>"
$PN"R6"15;
"UPI1_RX_DP<1>"
$PN"T7"16;
"UPI1_RX_DP<2>"
$PN"U8"17;
"UPI1_RX_DP<3>"
$PN"R8"18;
"UPI1_RX_DP<4>"
$PN"N10"19;
"UPI1_RX_DP<5>"
$PN"U10"20;
"UPI1_RX_DP<6>"
$PN"T11"21;
"UPI1_RX_DP<7>"
$PN"N12"22;
"UPI1_RX_DP<8>"
$PN"M13"23;
"UPI1_RX_DP<9>"
$PN"P13"24;
"UPI1_RX_DP<10>"
$PN"T15"25;
"UPI1_RX_DP<11>"
$PN"N16"26;
"UPI1_RX_DP<12>"
$PN"W16"27;
"UPI1_RX_DP<13>"
$PN"V17"28;
"UPI1_RX_DP<14>"
$PN"P19"29;
"UPI1_RX_DP<15>"
$PN"T19"30;
"UPI1_RX_DP<16>"
$PN"T21"31;
"UPI1_RX_DP<17>"
$PN"Y19"32;
"UPI1_RX_DP<18>"
$PN"W20"33;
"UPI1_RX_DP<19>"
$PN"AA20"34;
"UPI1_RX_DN<0>"
$PN"T5"5;
"UPI1_RX_DN<1>"
$PN"P7"6;
"UPI1_RX_DN<2>"
$PN"V7"7;
"UPI1_RX_DN<3>"
$PN"T9"8;
"UPI1_RX_DN<4>"
$PN"P9"9;
"UPI1_RX_DN<5>"
$PN"R10"10;
"UPI1_RX_DN<6>"
$PN"U12"11;
"UPI1_RX_DN<7>"
$PN"L12"12;
"UPI1_RX_DN<8>"
$PN"N14"13;
"UPI1_RX_DN<9>"
$PN"R12"14;
"UPI1_RX_DN<10>"
$PN"R16"35;
"UPI1_RX_DN<11>"
$PN"P17"36;
"UPI1_RX_DN<12>"
$PN"U16"37;
"UPI1_RX_DN<13>"
$PN"W18"38;
"UPI1_RX_DN<14>"
$PN"R20"39;
"UPI1_RX_DN<15>"
$PN"U18"40;
"UPI1_RX_DN<16>"
$PN"P21"41;
"UPI1_RX_DN<17>"
$PN"V19"42;
"UPI1_RX_DN<18>"
$PN"Y21"43;
"UPI1_RX_DN<19>"
$PN"AB19"44;
%"TAP"
"1","(-5300,1875)","2","mstr_standard","I9";
;
HDL_TAP"TRUE"
BODY_TYPE"PLUMBING"
CDS_LIB"mstr_standard";
"B \NAC \NWC"3;
"S \NAC"
BN"13"11;
END.
